(kicad_pcb
	(version 20260206)
	(generator "pcbnew")
	(generator_version "10.0")
	(general
		(thickness 1.6)
		(legacy_teardrops no)
	)
	(paper "A4")
	(title_block
		(title "v1-pdb — T6M_PDB_D_0927_0900.brd")
		(comment 1 "Open CloudServer (Microsoft) / footprints 153-161 of 321")
	)
	(layers
		(0 "F.Cu" signal "TOP")
		(4 "In1.Cu" signal "GND")
		(6 "In2.Cu" signal "IN1")
		(8 "In3.Cu" signal "VCC")
		(10 "In4.Cu" signal "VCC1")
		(12 "In5.Cu" signal "IN2")
		(14 "In6.Cu" signal "GND1")
		(2 "B.Cu" signal "BOTTOM")
		(9 "F.Adhes" user "F.Adhesive")
		(11 "B.Adhes" user "B.Adhesive")
		(13 "F.Paste" user "Package Geometry/Pastemask Top")
		(15 "B.Paste" user "Package Geometry/Pastemask Bottom")
		(5 "F.SilkS" user "Ref Des/Silkscreen Top")
		(7 "B.SilkS" user "Ref Des/Silkscreen Bottom")
		(1 "F.Mask" user "Board Geometry/Soldermask Top")
		(3 "B.Mask" user "Board Geometry/Soldermask Bottom")
		(17 "Dwgs.User" user "User.Drawings")
		(19 "Cmts.User" user "User.Comments")
		(21 "Eco1.User" user "User.Eco1")
		(23 "Eco2.User" user "User.Eco2")
		(25 "Edge.Cuts" user "Board Geometry/Outline")
		(27 "Margin" user)
		(31 "F.CrtYd" user "Package Geometry/Place Bound Top")
		(29 "B.CrtYd" user "Package Geometry/Place Bound Bottom")
		(35 "F.Fab" user "Ref Des/Assembly Top")
		(33 "B.Fab" user "Ref Des/Assembly Bottom")
	)
	(footprint ""
		(layer "F.Cu")
		(at 39.512494 -463.972148 90)
		(property "Reference" "R130"
			(at -0.669544 1.862074 0)
			(unlocked yes)
			(layer "F.SilkS")
			(effects
				(font
					(size 0.7874 0.5842)
					(thickness 0.1524)
				)
				(justify left)
			)
		)
		(property "Value" ""
			(at 0 0 90)
			(layer "F.Fab")
			(effects
				(font
					(size 1.27 1.27)
				)
			)
		)
		(duplicate_pad_numbers_are_jumpers no)
		(fp_line
			(start 0.7874 -0.4064)
			(end 0.7874 0.4064)
			(stroke
				(width 0.1524)
				(type default)
			)
			(layer "F.SilkS")
		)
		(fp_line
			(start -0.7874 -0.4064)
			(end 0.7874 -0.4064)
			(stroke
				(width 0.1524)
				(type default)
			)
			(layer "F.SilkS")
		)
		(fp_line
			(start 0.7874 0.4064)
			(end -0.7874 0.4064)
			(stroke
				(width 0.1524)
				(type default)
			)
			(layer "F.SilkS")
		)
		(fp_line
			(start -0.7874 0.4064)
			(end -0.7874 -0.4064)
			(stroke
				(width 0.1524)
				(type default)
			)
			(layer "F.SilkS")
		)
		(fp_poly
			(pts
				(xy -0.508 0.2794) (xy -0.508 0.2286) (xy -0.635 0.2286) (xy -0.635 -0.254) (xy -0.5334 -0.254)
				(xy -0.5334 -0.2794) (xy 0.5334 -0.2794) (xy 0.5334 -0.254) (xy 0.635 -0.254) (xy 0.635 0.254) (xy 0.5334 0.254)
				(xy 0.5334 0.2794)
			)
			(stroke
				(width 0)
				(type default)
			)
			(fill no)
			(layer "F.CrtYd")
		)
		(pad "1" smd rect
			(at 0.40005 0 90)
			(size 0.4572 0.508)
			(layers "F.Cu" "F.Mask" "F.Paste")
			(net "PSU6_REMOTE_P")
		)
		(pad "2" smd rect
			(at -0.40005 0 90)
			(size 0.4572 0.508)
			(layers "F.Cu" "F.Mask" "F.Paste")
			(net "PSU6_REMOTE_R2_P")
		)
	)
	(footprint ""
		(layer "F.Cu")
		(at 39.51478 -464.77047 -90)
		(property "Reference" "R98"
			(at -1.157224 -0.122428 90)
			(unlocked yes)
			(layer "F.SilkS")
			(effects
				(font
					(size 0.7874 0.5842)
					(thickness 0.1524)
				)
				(justify left)
			)
		)
		(property "Value" ""
			(at 0 0 270)
			(layer "F.Fab")
			(effects
				(font
					(size 1.27 1.27)
				)
			)
		)
		(duplicate_pad_numbers_are_jumpers no)
		(fp_line
			(start -0.7874 0.4064)
			(end -0.7874 -0.4064)
			(stroke
				(width 0.1524)
				(type default)
			)
			(layer "F.SilkS")
		)
		(fp_line
			(start 0.7874 0.4064)
			(end -0.7874 0.4064)
			(stroke
				(width 0.1524)
				(type default)
			)
			(layer "F.SilkS")
		)
		(fp_line
			(start -0.7874 -0.4064)
			(end 0.7874 -0.4064)
			(stroke
				(width 0.1524)
				(type default)
			)
			(layer "F.SilkS")
		)
		(fp_line
			(start 0.7874 -0.4064)
			(end 0.7874 0.4064)
			(stroke
				(width 0.1524)
				(type default)
			)
			(layer "F.SilkS")
		)
		(fp_poly
			(pts
				(xy -0.508 0.2794) (xy -0.508 0.2286) (xy -0.635 0.2286) (xy -0.635 -0.254) (xy -0.5334 -0.254)
				(xy -0.5334 -0.2794) (xy 0.5334 -0.2794) (xy 0.5334 -0.254) (xy 0.635 -0.254) (xy 0.635 0.254) (xy 0.5334 0.254)
				(xy 0.5334 0.2794)
			)
			(stroke
				(width 0)
				(type default)
			)
			(fill no)
			(layer "F.CrtYd")
		)
		(pad "1" smd rect
			(at 0.40005 0 270)
			(size 0.4572 0.508)
			(layers "F.Cu" "F.Mask" "F.Paste")
			(net "PSU6_REMOTE_P")
		)
		(pad "2" smd rect
			(at -0.40005 0 270)
			(size 0.4572 0.508)
			(layers "F.Cu" "F.Mask" "F.Paste")
			(net "PSU6_REMOTE_R_P")
		)
	)
	(footprint ""
		(layer "F.Cu")
		(at 50.150268 -350.765364 180)
		(property "Reference" "CE16"
			(at -4.708906 1.983994 0)
			(unlocked yes)
			(layer "F.SilkS")
			(effects
				(font
					(size 0.7874 0.5842)
					(thickness 0.1524)
				)
				(justify left)
			)
		)
		(property "Value" ""
			(at 0 0 180)
			(layer "F.Fab")
			(effects
				(font
					(size 1.27 1.27)
				)
			)
		)
		(duplicate_pad_numbers_are_jumpers no)
		(fp_line
			(start 0 -4.2672)
			(end 0 4.2672)
			(stroke
				(width 0.1524)
				(type default)
			)
			(layer "F.SilkS")
		)
		(fp_circle
			(center 0 0)
			(end -4.2672 0)
			(stroke
				(width 0.1524)
				(type default)
			)
			(fill no)
			(layer "F.SilkS")
		)
		(fp_poly
			(pts
				(arc
					(start 0 -4.2672)
					(mid 4.2672 0)
					(end 0 4.2672)
				)
			)
			(stroke
				(width 0)
				(type default)
			)
			(fill yes)
			(layer "F.SilkS")
		)
		(fp_poly
			(pts
				(xy -2.5146 -0.762) (xy -0.9906 -0.762) (xy -0.9906 0.762) (xy -2.5146 0.762)
			)
			(stroke
				(width 0)
				(type default)
			)
			(fill no)
			(layer "B.CrtYd")
		)
		(fp_poly
			(pts
				(arc
					(start 1.7526 0.762)
					(mid 2.291415 -0.538815)
					(end 0.9906 0)
				)
				(arc
					(start 0.9906 0.0254)
					(mid 1.206345 0.546255)
					(end 1.7272 0.762)
				)
			)
			(stroke
				(width 0)
				(type default)
			)
			(fill no)
			(layer "B.CrtYd")
		)
		(fp_poly
			(pts
				(arc
					(start -4.2672 0)
					(mid 4.2672 0)
					(end -4.2672 0)
				)
			)
			(stroke
				(width 0)
				(type default)
			)
			(fill no)
			(layer "F.CrtYd")
		)
		(fp_circle
			(center 0 0)
			(end -4.2672 0)
			(stroke
				(width 0.1)
				(type default)
			)
			(fill no)
			(layer "F.Fab")
		)
		(fp_text user "+"
			(at -5.00888 -0.427228 180)
			(unlocked yes)
			(layer "F.SilkS")
			(effects
				(font
					(size 0.7874 0.5842)
					(thickness 0.1524)
				)
				(justify left)
			)
		)
		(fp_text user "+"
			(at -5.6642 -0.34925 180)
			(unlocked yes)
			(layer "F.Fab")
			(effects
				(font
					(size 1.905 1.4224)
					(thickness 0.000001)
				)
				(justify left)
			)
		)
		(pad "1" thru_hole rect
			(at -1.75006 0 180)
			(size 1.397 1.397)
			(drill 0.9144)
			(layers "*.Cu" "*.Mask")
			(remove_unused_layers no)
			(net "P12V")
			(clearance 0.0127)
			(thermal_gap 0.0127)
			(padstack
				(mode front_inner_back)
				(layer "Inner"
					(shape circle)
					(size 1.397 1.397)
					(clearance 0.0127)
				)
				(layer "B.Cu"
					(shape rect)
					(size 1.397 1.397)
					(clearance 0.0127)
				)
			)
		)
		(pad "2" thru_hole circle
			(at 1.75006 0 180)
			(size 1.397 1.397)
			(drill 0.9144)
			(layers "*.Cu" "*.Mask")
			(remove_unused_layers no)
			(net "GND")
			(clearance 0.0127)
			(thermal_gap 0.0127)
		)
	)
	(footprint ""
		(layer "F.Cu")
		(at 26.928318 -196.6214)
		(property "Reference" "R6"
			(at -3.177032 0.103886 0)
			(unlocked yes)
			(layer "F.SilkS")
			(effects
				(font
					(size 0.7874 0.5842)
					(thickness 0.1524)
				)
				(justify left)
			)
		)
		(property "Value" ""
			(at 0 0 0)
			(layer "F.Fab")
			(effects
				(font
					(size 1.27 1.27)
				)
			)
		)
		(duplicate_pad_numbers_are_jumpers no)
		(fp_line
			(start -0.7874 -0.4064)
			(end 0.7874 -0.4064)
			(stroke
				(width 0.1524)
				(type default)
			)
			(layer "F.SilkS")
		)
		(fp_line
			(start -0.7874 0.4064)
			(end -0.7874 -0.4064)
			(stroke
				(width 0.1524)
				(type default)
			)
			(layer "F.SilkS")
		)
		(fp_line
			(start 0.7874 -0.4064)
			(end 0.7874 0.4064)
			(stroke
				(width 0.1524)
				(type default)
			)
			(layer "F.SilkS")
		)
		(fp_line
			(start 0.7874 0.4064)
			(end -0.7874 0.4064)
			(stroke
				(width 0.1524)
				(type default)
			)
			(layer "F.SilkS")
		)
		(fp_poly
			(pts
				(xy -0.508 0.2794) (xy -0.508 0.2286) (xy -0.635 0.2286) (xy -0.635 -0.254) (xy -0.5334 -0.254)
				(xy -0.5334 -0.2794) (xy 0.5334 -0.2794) (xy 0.5334 -0.254) (xy 0.635 -0.254) (xy 0.635 0.254) (xy 0.5334 0.254)
				(xy 0.5334 0.2794)
			)
			(stroke
				(width 0)
				(type default)
			)
			(fill no)
			(layer "F.CrtYd")
		)
		(pad "1" smd rect
			(at 0.40005 0)
			(size 0.4572 0.508)
			(layers "F.Cu" "F.Mask" "F.Paste")
			(net "PSU3_REMOTE_N")
		)
		(pad "2" smd rect
			(at -0.40005 0)
			(size 0.4572 0.508)
			(layers "F.Cu" "F.Mask" "F.Paste")
			(net "GND")
		)
	)
	(footprint ""
		(layer "F.Cu")
		(at 68.972938 -60.671456 -90)
		(property "Reference" "C8"
			(at -2.737104 0.062992 90)
			(unlocked yes)
			(layer "F.SilkS")
			(effects
				(font
					(size 0.7874 0.5842)
					(thickness 0.1524)
				)
			)
		)
		(property "Value" ""
			(at 0 0 270)
			(layer "F.Fab")
			(effects
				(font
					(size 1.27 1.27)
				)
			)
		)
		(duplicate_pad_numbers_are_jumpers no)
		(fp_line
			(start -1.2954 0.5842)
			(end -1.2954 -0.5842)
			(stroke
				(width 0.1524)
				(type default)
			)
			(layer "F.SilkS")
		)
		(fp_line
			(start 1.2954 0.5842)
			(end -1.2954 0.5842)
			(stroke
				(width 0.1524)
				(type default)
			)
			(layer "F.SilkS")
		)
		(fp_line
			(start -1.2954 -0.5842)
			(end 1.2954 -0.5842)
			(stroke
				(width 0.1524)
				(type default)
			)
			(layer "F.SilkS")
		)
		(fp_line
			(start 0 -0.5842)
			(end 0 0.5842)
			(stroke
				(width 0.1524)
				(type default)
			)
			(layer "F.SilkS")
		)
		(fp_line
			(start 1.2954 -0.5842)
			(end 1.2954 0.5842)
			(stroke
				(width 0.1524)
				(type default)
			)
			(layer "F.SilkS")
		)
		(fp_poly
			(pts
				(xy 0.8636 -0.4572) (xy 0.8636 -0.3556) (xy 1.143 -0.3556) (xy 1.143 0.3556) (xy 0.8636 0.3556)
				(xy 0.8636 0.4572) (xy -0.8636 0.4572) (xy -0.8636 0.3556) (xy -1.143 0.3556) (xy -1.143 -0.3556)
				(xy -0.8636 -0.3556) (xy -0.8636 -0.4572)
			)
			(stroke
				(width 0)
				(type default)
			)
			(fill no)
			(layer "F.CrtYd")
		)
		(fp_line
			(start -0.884936 0.504952)
			(end -0.884936 -0.504952)
			(stroke
				(width 0.1)
				(type default)
			)
			(layer "F.Fab")
		)
		(fp_line
			(start 0.884936 0.504952)
			(end -0.884936 0.504952)
			(stroke
				(width 0.1)
				(type default)
			)
			(layer "F.Fab")
		)
		(fp_line
			(start -0.884936 -0.504952)
			(end 0.884936 -0.504952)
			(stroke
				(width 0.1)
				(type default)
			)
			(layer "F.Fab")
		)
		(fp_line
			(start 0.884936 -0.504952)
			(end 0.884936 0.504952)
			(stroke
				(width 0.1)
				(type default)
			)
			(layer "F.Fab")
		)
		(pad "1" smd rect
			(at 0.7366 0)
			(size 0.7112 0.8128)
			(layers "F.Cu" "F.Mask" "F.Paste")
			(net "P12V")
		)
		(pad "2" smd rect
			(at -0.7366 0)
			(size 0.7112 0.8128)
			(layers "F.Cu" "F.Mask" "F.Paste")
			(net "GND")
		)
	)
	(footprint ""
		(layer "F.Cu")
		(at 25.931622 -99.36988)
		(property "Reference" "R46"
			(at -4.080256 -0.075692 0)
			(unlocked yes)
			(layer "F.SilkS")
			(effects
				(font
					(size 0.7874 0.5842)
					(thickness 0.1524)
				)
				(justify left)
			)
		)
		(property "Value" ""
			(at 0 0 0)
			(layer "F.Fab")
			(effects
				(font
					(size 1.27 1.27)
				)
			)
		)
		(duplicate_pad_numbers_are_jumpers no)
		(fp_line
			(start -0.7874 -0.4064)
			(end 0.7874 -0.4064)
			(stroke
				(width 0.1524)
				(type default)
			)
			(layer "F.SilkS")
		)
		(fp_line
			(start -0.7874 0.4064)
			(end -0.7874 -0.4064)
			(stroke
				(width 0.1524)
				(type default)
			)
			(layer "F.SilkS")
		)
		(fp_line
			(start 0.7874 -0.4064)
			(end 0.7874 0.4064)
			(stroke
				(width 0.1524)
				(type default)
			)
			(layer "F.SilkS")
		)
		(fp_line
			(start 0.7874 0.4064)
			(end -0.7874 0.4064)
			(stroke
				(width 0.1524)
				(type default)
			)
			(layer "F.SilkS")
		)
		(fp_poly
			(pts
				(xy -0.508 0.2794) (xy -0.508 0.2286) (xy -0.635 0.2286) (xy -0.635 -0.254) (xy -0.5334 -0.254)
				(xy -0.5334 -0.2794) (xy 0.5334 -0.2794) (xy 0.5334 -0.254) (xy 0.635 -0.254) (xy 0.635 0.254) (xy 0.5334 0.254)
				(xy 0.5334 0.2794)
			)
			(stroke
				(width 0)
				(type default)
			)
			(fill no)
			(layer "F.CrtYd")
		)
		(pad "1" smd rect
			(at 0.40005 0)
			(size 0.4572 0.508)
			(layers "F.Cu" "F.Mask" "F.Paste")
			(net "PSU2_PS_KILL")
		)
		(pad "2" smd rect
			(at -0.40005 0)
			(size 0.4572 0.508)
			(layers "F.Cu" "F.Mask" "F.Paste")
			(net "GND")
		)
	)
	(footprint ""
		(layer "F.Cu")
		(at 25.857708 -360.550968)
		(property "Reference" "R59"
			(at -3.917442 -0.225298 0)
			(unlocked yes)
			(layer "F.SilkS")
			(effects
				(font
					(size 0.7874 0.5842)
					(thickness 0.1524)
				)
				(justify left)
			)
		)
		(property "Value" ""
			(at 0 0 0)
			(layer "F.Fab")
			(effects
				(font
					(size 1.27 1.27)
				)
			)
		)
		(duplicate_pad_numbers_are_jumpers no)
		(fp_line
			(start -0.7874 -0.4064)
			(end 0.7874 -0.4064)
			(stroke
				(width 0.1524)
				(type default)
			)
			(layer "F.SilkS")
		)
		(fp_line
			(start -0.7874 0.4064)
			(end -0.7874 -0.4064)
			(stroke
				(width 0.1524)
				(type default)
			)
			(layer "F.SilkS")
		)
		(fp_line
			(start 0.7874 -0.4064)
			(end 0.7874 0.4064)
			(stroke
				(width 0.1524)
				(type default)
			)
			(layer "F.SilkS")
		)
		(fp_line
			(start 0.7874 0.4064)
			(end -0.7874 0.4064)
			(stroke
				(width 0.1524)
				(type default)
			)
			(layer "F.SilkS")
		)
		(fp_poly
			(pts
				(xy -0.508 0.2794) (xy -0.508 0.2286) (xy -0.635 0.2286) (xy -0.635 -0.254) (xy -0.5334 -0.254)
				(xy -0.5334 -0.2794) (xy 0.5334 -0.2794) (xy 0.5334 -0.254) (xy 0.635 -0.254) (xy 0.635 0.254) (xy 0.5334 0.254)
				(xy 0.5334 0.2794)
			)
			(stroke
				(width 0)
				(type default)
			)
			(fill no)
			(layer "F.CrtYd")
		)
		(pad "1" smd rect
			(at 0.40005 0)
			(size 0.4572 0.508)
			(layers "F.Cu" "F.Mask" "F.Paste")
			(net "PSU5_RESET")
		)
		(pad "2" smd rect
			(at -0.40005 0)
			(size 0.4572 0.508)
			(layers "F.Cu" "F.Mask" "F.Paste")
			(net "GND")
		)
	)
	(footprint ""
		(layer "F.Cu")
		(at 26.068274 -181.847998)
		(property "Reference" "R73"
			(at -3.997198 0.128524 0)
			(unlocked yes)
			(layer "F.SilkS")
			(effects
				(font
					(size 0.7874 0.5842)
					(thickness 0.1524)
				)
				(justify left)
			)
		)
		(property "Value" ""
			(at 0 0 0)
			(layer "F.Fab")
			(effects
				(font
					(size 1.27 1.27)
				)
			)
		)
		(duplicate_pad_numbers_are_jumpers no)
		(fp_line
			(start -0.7874 -0.4064)
			(end 0.7874 -0.4064)
			(stroke
				(width 0.1524)
				(type default)
			)
			(layer "F.SilkS")
		)
		(fp_line
			(start -0.7874 0.4064)
			(end -0.7874 -0.4064)
			(stroke
				(width 0.1524)
				(type default)
			)
			(layer "F.SilkS")
		)
		(fp_line
			(start 0.7874 -0.4064)
			(end 0.7874 0.4064)
			(stroke
				(width 0.1524)
				(type default)
			)
			(layer "F.SilkS")
		)
		(fp_line
			(start 0.7874 0.4064)
			(end -0.7874 0.4064)
			(stroke
				(width 0.1524)
				(type default)
			)
			(layer "F.SilkS")
		)
		(fp_poly
			(pts
				(xy -0.508 0.2794) (xy -0.508 0.2286) (xy -0.635 0.2286) (xy -0.635 -0.254) (xy -0.5334 -0.254)
				(xy -0.5334 -0.2794) (xy 0.5334 -0.2794) (xy 0.5334 -0.254) (xy 0.635 -0.254) (xy 0.635 0.254) (xy 0.5334 0.254)
				(xy 0.5334 0.2794)
			)
			(stroke
				(width 0)
				(type default)
			)
			(fill no)
			(layer "F.CrtYd")
		)
		(pad "1" smd rect
			(at 0.40005 0)
			(size 0.4572 0.508)
			(layers "F.Cu" "F.Mask" "F.Paste")
			(net "PSU3_RESET")
		)
		(pad "2" smd rect
			(at -0.40005 0)
			(size 0.4572 0.508)
			(layers "F.Cu" "F.Mask" "F.Paste")
			(net "GND")
		)
	)
	(footprint ""
		(layer "F.Cu")
		(at 49.949608 -18.56867 180)
		(property "Reference" "CE1"
			(at -4.548124 -1.308608 0)
			(unlocked yes)
			(layer "F.SilkS")
			(effects
				(font
					(size 0.7874 0.5842)
					(thickness 0.1524)
				)
				(justify left)
			)
		)
		(property "Value" ""
			(at 0 0 180)
			(layer "F.Fab")
			(effects
				(font
					(size 1.27 1.27)
				)
			)
		)
		(duplicate_pad_numbers_are_jumpers no)
		(fp_line
			(start 0 -4.2672)
			(end 0 4.2672)
			(stroke
				(width 0.1524)
				(type default)
			)
			(layer "F.SilkS")
		)
		(fp_circle
			(center 0 0)
			(end -4.2672 0)
			(stroke
				(width 0.1524)
				(type default)
			)
			(fill no)
			(layer "F.SilkS")
		)
		(fp_poly
			(pts
				(arc
					(start 0 -4.2672)
					(mid 4.2672 0)
					(end 0 4.2672)
				)
			)
			(stroke
				(width 0)
				(type default)
			)
			(fill yes)
			(layer "F.SilkS")
		)
		(fp_poly
			(pts
				(xy -2.5146 -0.762) (xy -0.9906 -0.762) (xy -0.9906 0.762) (xy -2.5146 0.762)
			)
			(stroke
				(width 0)
				(type default)
			)
			(fill no)
			(layer "B.CrtYd")
		)
		(fp_poly
			(pts
				(arc
					(start 1.7526 0.762)
					(mid 2.291415 -0.538815)
					(end 0.9906 0)
				)
				(arc
					(start 0.9906 0.0254)
					(mid 1.206345 0.546255)
					(end 1.7272 0.762)
				)
			)
			(stroke
				(width 0)
				(type default)
			)
			(fill no)
			(layer "B.CrtYd")
		)
		(fp_poly
			(pts
				(arc
					(start -4.2672 0)
					(mid 4.2672 0)
					(end -4.2672 0)
				)
			)
			(stroke
				(width 0)
				(type default)
			)
			(fill no)
			(layer "F.CrtYd")
		)
		(fp_circle
			(center 0 0)
			(end -4.2672 0)
			(stroke
				(width 0.1)
				(type default)
			)
			(fill no)
			(layer "F.Fab")
		)
		(fp_text user "+"
			(at -5.15239 -2.408428 180)
			(unlocked yes)
			(layer "F.SilkS")
			(effects
				(font
					(size 0.7874 0.5842)
					(thickness 0.1524)
				)
				(justify left)
			)
		)
		(fp_text user "+"
			(at -5.6642 -0.34925 180)
			(unlocked yes)
			(layer "F.Fab")
			(effects
				(font
					(size 1.905 1.4224)
					(thickness 0.000001)
				)
				(justify left)
			)
		)
		(pad "1" thru_hole rect
			(at -1.75006 0 180)
			(size 1.397 1.397)
			(drill 0.9144)
			(layers "*.Cu" "*.Mask")
			(remove_unused_layers no)
			(net "P12V")
			(clearance 0.0127)
			(thermal_gap 0.0127)
			(padstack
				(mode front_inner_back)
				(layer "Inner"
					(shape circle)
					(size 1.397 1.397)
					(clearance 0.0127)
				)
				(layer "B.Cu"
					(shape rect)
					(size 1.397 1.397)
					(clearance 0.0127)
				)
			)
		)
		(pad "2" thru_hole circle
			(at 1.75006 0 180)
			(size 1.397 1.397)
			(drill 0.9144)
			(layers "*.Cu" "*.Mask")
			(remove_unused_layers no)
			(net "GND")
			(clearance 0.0127)
			(thermal_gap 0.0127)
		)
	)
)
